# S9S_MB_2U (Grand Teton) — schematic netlist excerpt (pin names and nets, part order shuffled) for the footprints in the layout excerpt that follows; sources: Cadence DE-HDL packaged netlist, KiCad conversion of 03242023_DA0F0TMBIJ0_F0T_Motherboard_J_brd_V01_OCP.brd

PR354  Q_RES  8.87K 1% EMPTY  pkg 0402LF  page 271 : A = PVCCFA_EHV_FIVRA_CPU0_LSET1 ; B = GND
R1745  Q_RES  0 5% EMPTY  pkg 0402LF  page 244 : A = FM_COMP_P3V3_AUX_ENIN ; B = FM_PFR_DSW_PWROK_N

(kicad_pcb
	(version 20260206)
	(generator "pcbnew")
	(generator_version "10.0")
	(general
		(thickness 1.6)
		(legacy_teardrops no)
	)
	(paper "A4")
	(title_block
		(title "03242023_DA0F0TMBIJ0_F0T_Motherboard_J_brd_V01_OCP.brd")
		(comment 1 "Grand Teton / footprints 1452-1453 of 6105")
	)
	(layers
		(0 "F.Cu" signal "TOP")
		(4 "In1.Cu" signal "GND")
		(6 "In2.Cu" signal "IN1")
		(8 "In3.Cu" signal "GND1")
		(10 "In4.Cu" signal "IN2")
		(12 "In5.Cu" signal "GND2")
		(14 "In6.Cu" signal "IN3")
		(16 "In7.Cu" signal "GND3")
		(18 "In8.Cu" signal "VCC")
		(20 "In9.Cu" signal "VCC1")
		(22 "In10.Cu" signal "GND4")
		(24 "In11.Cu" signal "IN4")
		(26 "In12.Cu" signal "GND5")
		(28 "In13.Cu" signal "IN5")
		(30 "In14.Cu" signal "GND6")
		(32 "In15.Cu" signal "IN6")
		(34 "In16.Cu" signal "GND7")
		(2 "B.Cu" signal "BOTTOM")
		(9 "F.Adhes" user "F.Adhesive")
		(11 "B.Adhes" user "B.Adhesive")
		(13 "F.Paste" user "Package Geometry/Pastemask Top")
		(15 "B.Paste" user "Package Geometry/Pastemask Bottom")
		(5 "F.SilkS" user "Ref Des/Silkscreen Top")
		(7 "B.SilkS" user "Ref Des/Silkscreen Bottom")
		(1 "F.Mask" user "Board Geometry/Soldermask Top")
		(3 "B.Mask" user "Board Geometry/Soldermask Bottom")
		(17 "Dwgs.User" user "User.Drawings")
		(19 "Cmts.User" user "User.Comments")
		(21 "Eco1.User" user "User.Eco1")
		(23 "Eco2.User" user "User.Eco2")
		(25 "Edge.Cuts" user "Board Geometry/Outline")
		(27 "Margin" user)
		(31 "F.CrtYd" user "Package Geometry/Place Bound Top")
		(29 "B.CrtYd" user "Package Geometry/Place Bound Bottom")
		(35 "F.Fab" user "Ref Des/Assembly Top")
		(33 "B.Fab" user "Ref Des/Assembly Bottom")
	)
	(footprint ""
		(layer "F.Cu")
		(at 209.74558 -133.878828 180)
		(property "Reference" "R1745"
			(at 0 0 180)
			(layer "F.SilkS")
			(hide yes)
			(effects
				(font
					(size 1.27 1.27)
				)
			)
		)
		(property "Value" ""
			(at 0 0 180)
			(layer "F.Fab")
			(effects
				(font
					(size 1.27 1.27)
				)
			)
		)
		(duplicate_pad_numbers_are_jumpers no)
		(fp_line
			(start 0.7874 0.4064)
			(end -0.7874 0.4064)
			(stroke
				(width 0.1524)
				(type default)
			)
			(layer "F.SilkS")
		)
		(fp_line
			(start 0.7874 -0.4064)
			(end 0.7874 0.4064)
			(stroke
				(width 0.1524)
				(type default)
			)
			(layer "F.SilkS")
		)
		(fp_line
			(start -0.7874 0.4064)
			(end -0.7874 -0.4064)
			(stroke
				(width 0.1524)
				(type default)
			)
			(layer "F.SilkS")
		)
		(fp_line
			(start -0.7874 -0.4064)
			(end 0.7874 -0.4064)
			(stroke
				(width 0.1524)
				(type default)
			)
			(layer "F.SilkS")
		)
		(fp_line
			(start 0.67945 0.3048)
			(end 0.120396 0.3048)
			(stroke
				(width 0.1)
				(type default)
			)
			(layer "F.Fab")
		)
		(fp_line
			(start 0.67945 -0.3048)
			(end 0.67945 0.3048)
			(stroke
				(width 0.1)
				(type default)
			)
			(layer "F.Fab")
		)
		(fp_line
			(start 0.12065 -0.2794)
			(end 0.12065 -0.3048)
			(stroke
				(width 0.1)
				(type default)
			)
			(layer "F.Fab")
		)
		(fp_line
			(start 0.12065 -0.3048)
			(end 0.67945 -0.3048)
			(stroke
				(width 0.1)
				(type default)
			)
			(layer "F.Fab")
		)
		(fp_line
			(start 0.120396 0.3048)
			(end 0.120396 0.2794)
			(stroke
				(width 0.1)
				(type default)
			)
			(layer "F.Fab")
		)
		(fp_line
			(start 0.120396 0.2794)
			(end -0.12065 0.2794)
			(stroke
				(width 0.1)
				(type default)
			)
			(layer "F.Fab")
		)
		(fp_line
			(start -0.12065 0.3048)
			(end -0.67945 0.3048)
			(stroke
				(width 0.1)
				(type default)
			)
			(layer "F.Fab")
		)
		(fp_line
			(start -0.12065 0.2794)
			(end -0.12065 0.3048)
			(stroke
				(width 0.1)
				(type default)
			)
			(layer "F.Fab")
		)
		(fp_line
			(start -0.12065 -0.2794)
			(end 0.12065 -0.2794)
			(stroke
				(width 0.1)
				(type default)
			)
			(layer "F.Fab")
		)
		(fp_line
			(start -0.12065 -0.305054)
			(end -0.12065 -0.2794)
			(stroke
				(width 0.1)
				(type default)
			)
			(layer "F.Fab")
		)
		(fp_line
			(start -0.67945 0.3048)
			(end -0.67945 -0.305054)
			(stroke
				(width 0.1)
				(type default)
			)
			(layer "F.Fab")
		)
		(fp_line
			(start -0.67945 -0.305054)
			(end -0.12065 -0.305054)
			(stroke
				(width 0.1)
				(type default)
			)
			(layer "F.Fab")
		)
		(pad "1" smd circle
			(at -0.40005 0 180)
			(size 0 0)
			(layers "F.Cu" "F.Mask" "F.Paste")
			(net "FM_COMP_P3V3_AUX_ENIN")
		)
		(pad "2" smd circle
			(at 0.40005 0 180)
			(size 0 0)
			(layers "F.Cu" "F.Mask" "F.Paste")
			(net "FM_PFR_DSW_PWROK_N")
		)
	)
	(footprint ""
		(layer "F.Cu")
		(at 414.869122 -367.231676)
		(property "Reference" "PR354"
			(at 0 0 0)
			(layer "F.SilkS")
			(hide yes)
			(effects
				(font
					(size 1.27 1.27)
				)
			)
		)
		(property "Value" ""
			(at 0 0 0)
			(layer "F.Fab")
			(effects
				(font
					(size 1.27 1.27)
				)
			)
		)
		(duplicate_pad_numbers_are_jumpers no)
		(fp_line
			(start -0.7874 -0.4064)
			(end 0.7874 -0.4064)
			(stroke
				(width 0.1524)
				(type default)
			)
			(layer "F.SilkS")
		)
		(fp_line
			(start -0.7874 0.4064)
			(end -0.7874 -0.4064)
			(stroke
				(width 0.1524)
				(type default)
			)
			(layer "F.SilkS")
		)
		(fp_line
			(start 0.7874 -0.4064)
			(end 0.7874 0.4064)
			(stroke
				(width 0.1524)
				(type default)
			)
			(layer "F.SilkS")
		)
		(fp_line
			(start 0.7874 0.4064)
			(end -0.7874 0.4064)
			(stroke
				(width 0.1524)
				(type default)
			)
			(layer "F.SilkS")
		)
		(fp_line
			(start -0.67945 -0.305054)
			(end -0.12065 -0.305054)
			(stroke
				(width 0.1)
				(type default)
			)
			(layer "F.Fab")
		)
		(fp_line
			(start -0.67945 0.3048)
			(end -0.67945 -0.305054)
			(stroke
				(width 0.1)
				(type default)
			)
			(layer "F.Fab")
		)
		(fp_line
			(start -0.12065 -0.305054)
			(end -0.12065 -0.2794)
			(stroke
				(width 0.1)
				(type default)
			)
			(layer "F.Fab")
		)
		(fp_line
			(start -0.12065 -0.2794)
			(end 0.12065 -0.2794)
			(stroke
				(width 0.1)
				(type default)
			)
			(layer "F.Fab")
		)
		(fp_line
			(start -0.12065 0.2794)
			(end -0.12065 0.3048)
			(stroke
				(width 0.1)
				(type default)
			)
			(layer "F.Fab")
		)
		(fp_line
			(start -0.12065 0.3048)
			(end -0.67945 0.3048)
			(stroke
				(width 0.1)
				(type default)
			)
			(layer "F.Fab")
		)
		(fp_line
			(start 0.120396 0.2794)
			(end -0.12065 0.2794)
			(stroke
				(width 0.1)
				(type default)
			)
			(layer "F.Fab")
		)
		(fp_line
			(start 0.120396 0.3048)
			(end 0.120396 0.2794)
			(stroke
				(width 0.1)
				(type default)
			)
			(layer "F.Fab")
		)
		(fp_line
			(start 0.12065 -0.3048)
			(end 0.67945 -0.3048)
			(stroke
				(width 0.1)
				(type default)
			)
			(layer "F.Fab")
		)
		(fp_line
			(start 0.12065 -0.2794)
			(end 0.12065 -0.3048)
			(stroke
				(width 0.1)
				(type default)
			)
			(layer "F.Fab")
		)
		(fp_line
			(start 0.67945 -0.3048)
			(end 0.67945 0.3048)
			(stroke
				(width 0.1)
				(type default)
			)
			(layer "F.Fab")
		)
		(fp_line
			(start 0.67945 0.3048)
			(end 0.120396 0.3048)
			(stroke
				(width 0.1)
				(type default)
			)
			(layer "F.Fab")
		)
		(pad "1" smd circle
			(at -0.40005 0)
			(size 0 0)
			(layers "F.Cu" "F.Mask" "F.Paste")
			(net "PVCCFA_EHV_FIVRA_CPU0_LSET1")
		)
		(pad "2" smd circle
			(at 0.40005 0)
			(size 0 0)
			(layers "F.Cu" "F.Mask" "F.Paste")
			(net "GND")
		)
	)
)
